(kicad_pcb
	(version 20260206)
	(generator "pcbnew")
	(generator_version "10.0")
	(general
		(thickness 1.6)
		(legacy_teardrops no)
	)
	(paper "A4")
	(title_block
		(title "Bryce Canyon_SCC_16316-1_OCP.brd")
		(comment 1 "Bryce Canyon / footprints 103-111 of 1561")
	)
	(layers
		(0 "F.Cu" signal "TOP")
		(4 "In1.Cu" signal "L2GND")
		(6 "In2.Cu" signal "L3")
		(8 "In3.Cu" signal "L4VCC")
		(10 "In4.Cu" signal "L5VCC")
		(12 "In5.Cu" signal "L6")
		(14 "In6.Cu" signal "L7GND")
		(2 "B.Cu" signal "BOTTOM")
		(9 "F.Adhes" user "F.Adhesive")
		(11 "B.Adhes" user "B.Adhesive")
		(13 "F.Paste" user "Package Geometry/Pastemask Top")
		(15 "B.Paste" user "Package Geometry/Pastemask Bottom")
		(5 "F.SilkS" user "Ref Des/Silkscreen Top")
		(7 "B.SilkS" user "Ref Des/Silkscreen Bottom")
		(1 "F.Mask" user "Board Geometry/Soldermask Top")
		(3 "B.Mask" user "Board Geometry/Soldermask Bottom")
		(17 "Dwgs.User" user "User.Drawings")
		(19 "Cmts.User" user "User.Comments")
		(21 "Eco1.User" user "User.Eco1")
		(23 "Eco2.User" user "User.Eco2")
		(25 "Edge.Cuts" user "Board Geometry/Outline")
		(27 "Margin" user)
		(31 "F.CrtYd" user "Package Geometry/Place Bound Top")
		(29 "B.CrtYd" user "Package Geometry/Place Bound Bottom")
		(35 "F.Fab" user "Ref Des/Assembly Top")
		(33 "B.Fab" user "Ref Des/Assembly Bottom")
	)
	(footprint ""
		(layer "F.Cu")
		(at 165.461442 -84.151978 90)
		(property "Reference" "C636"
			(at 0 0 90)
			(layer "F.SilkS")
			(hide yes)
			(effects
				(font
					(size 1.27 1.27)
				)
			)
		)
		(property "Value" "SC10U16V5KX-7-GP-U"
			(at -0.0762 -6.1214 90)
			(unlocked yes)
			(layer "F.Fab")
			(hide yes)
			(effects
				(font
					(size 1.016 1.016)
					(thickness 0.1524)
				)
			)
		)
		(property "Device Type" "C805H58"
			(at -0.0762 -8.1534 90)
			(unlocked yes)
			(layer "F.Fab")
			(hide yes)
			(effects
				(font
					(size 1.016 1.016)
					(thickness 0.1524)
				)
			)
		)
		(duplicate_pad_numbers_are_jumpers no)
		(fp_line
			(start 0.635 0)
			(end -0.635 0)
			(stroke
				(width 0.508)
				(type default)
			)
			(layer "F.SilkS")
		)
		(fp_rect
			(start -0.9652 1.778)
			(end 0.9652 -1.778)
			(stroke
				(width 0)
				(type default)
			)
			(fill no)
			(layer "F.CrtYd")
		)
		(fp_poly
			(pts
				(xy -0.9652 -1.778) (xy 0.9652 -1.778) (xy 0.9652 1.778) (xy -0.9652 1.778)
			)
			(stroke
				(width 0)
				(type default)
			)
			(fill no)
			(layer "F.Fab")
		)
		(pad "1" smd rect
			(at 0 -0.9652 90)
			(size 1.397 1.143)
			(layers "F.Cu" "F.Mask" "F.Paste")
			(net "P12V_SYBY_VDD_U6")
		)
		(pad "2" smd rect
			(at 0 0.9652 90)
			(size 1.397 1.143)
			(layers "F.Cu" "F.Mask" "F.Paste")
			(net "GND")
		)
	)
	(footprint ""
		(layer "F.Cu")
		(at 196.342 -80.2132)
		(property "Reference" "TP166"
			(at 0 0 0)
			(layer "F.SilkS")
			(hide yes)
			(effects
				(font
					(size 1.27 1.27)
				)
			)
		)
		(property "Value" "TPAD28-2-GP"
			(at -0.0127 -1.6637 0)
			(unlocked yes)
			(layer "F.Fab")
			(hide yes)
			(effects
				(font
					(size 1.016 1.016)
					(thickness 0.1524)
				)
			)
		)
		(property "Device Type" "TPAD28"
			(at -0.0127 -3.1877 0)
			(unlocked yes)
			(layer "F.Fab")
			(hide yes)
			(effects
				(font
					(size 1.016 1.016)
					(thickness 0.1524)
				)
			)
		)
		(duplicate_pad_numbers_are_jumpers no)
		(fp_poly
			(pts
				(arc
					(start 0.3556 0)
					(mid -0.3556 0)
					(end 0.3556 0)
				)
			)
			(stroke
				(width 0)
				(type default)
			)
			(fill no)
			(layer "F.CrtYd")
		)
		(fp_poly
			(pts
				(arc
					(start 0.6096 0)
					(mid -0.6096 0)
					(end 0.6096 0)
				)
			)
			(stroke
				(width 0)
				(type default)
			)
			(fill no)
			(layer "F.Fab")
		)
		(pad "1" smd circle
			(at 0 0)
			(size 0.7112 0.7112)
			(layers "F.Cu" "F.Mask" "F.Paste")
			(net "TEMP2_ALERT")
		)
	)
	(footprint ""
		(layer "F.Cu")
		(at 57.431686 -21.500846 180)
		(property "Reference" "U47"
			(at 0 0 180)
			(layer "F.SilkS")
			(hide yes)
			(effects
				(font
					(size 1.27 1.27)
				)
			)
		)
		(property "Value" "SNLVC1G126DCKR-GP"
			(at -2.3368 -8.6868 180)
			(unlocked yes)
			(layer "F.Fab")
			(hide yes)
			(effects
				(font
					(size 1.016 1.016)
					(thickness 0.1524)
				)
			)
		)
		(property "Device Type" "SC70-5H44"
			(at -2.3114 -10.414 180)
			(unlocked yes)
			(layer "F.Fab")
			(hide yes)
			(effects
				(font
					(size 1.016 1.016)
					(thickness 0.1524)
				)
			)
		)
		(duplicate_pad_numbers_are_jumpers no)
		(fp_line
			(start 1.3843 -1.8034)
			(end 1.3843 -1.1176)
			(stroke
				(width 0.3302)
				(type default)
			)
			(layer "F.SilkS")
		)
		(fp_line
			(start 1.27 1.7018)
			(end -1.27 1.7018)
			(stroke
				(width 0.1524)
				(type default)
			)
			(layer "F.SilkS")
		)
		(fp_line
			(start 1.27 -1.7018)
			(end 1.27 1.7018)
			(stroke
				(width 0.1524)
				(type default)
			)
			(layer "F.SilkS")
		)
		(fp_line
			(start 0.6604 -1.8034)
			(end 1.3843 -1.8034)
			(stroke
				(width 0.3302)
				(type default)
			)
			(layer "F.SilkS")
		)
		(fp_line
			(start -1.27 1.7018)
			(end -1.27 -1.7018)
			(stroke
				(width 0.1524)
				(type default)
			)
			(layer "F.SilkS")
		)
		(fp_line
			(start -1.27 -1.7018)
			(end 1.27 -1.7018)
			(stroke
				(width 0.1524)
				(type default)
			)
			(layer "F.SilkS")
		)
		(fp_rect
			(start -1.524 1.9558)
			(end 1.524 -1.9558)
			(stroke
				(width 0)
				(type default)
			)
			(fill no)
			(layer "F.CrtYd")
		)
		(fp_poly
			(pts
				(xy -1.524 -1.9558) (xy 1.524 -1.9558) (xy 1.524 1.9558) (xy -1.524 1.9558)
			)
			(stroke
				(width 0)
				(type default)
			)
			(fill no)
			(layer "F.Fab")
		)
		(pad "1" smd rect
			(at 0.65024 -0.8255 180)
			(size 0.4064 1.2192)
			(layers "F.Cu" "F.Mask" "F.Paste")
			(net "U47_OE")
		)
		(pad "2" smd rect
			(at 0 -0.8255 180)
			(size 0.4064 1.2192)
			(layers "F.Cu" "F.Mask" "F.Paste")
			(net "SCC_STBY_PWR_EN")
		)
		(pad "3" smd rect
			(at -0.65024 -0.8255 180)
			(size 0.4064 1.2192)
			(layers "F.Cu" "F.Mask" "F.Paste")
			(net "GND")
		)
		(pad "4" smd rect
			(at -0.65024 0.8255 180)
			(size 0.4064 1.2192)
			(layers "F.Cu" "F.Mask" "F.Paste")
			(net "SCC_STBY_PWR_BUF_EN")
		)
		(pad "5" smd rect
			(at 0.65024 0.8255 180)
			(size 0.4064 1.2192)
			(layers "F.Cu" "F.Mask" "F.Paste")
			(net "P3V3_DPB")
		)
	)
	(footprint ""
		(layer "F.Cu")
		(at 7.6962 -55.245 -90)
		(property "Reference" "C108"
			(at 0 0 270)
			(layer "F.SilkS")
			(hide yes)
			(effects
				(font
					(size 1.27 1.27)
				)
			)
		)
		(property "Value" "SC2D2U25V5KX-2-GP"
			(at -0.0762 -6.1214 270)
			(unlocked yes)
			(layer "F.Fab")
			(hide yes)
			(effects
				(font
					(size 1.016 1.016)
					(thickness 0.1524)
				)
			)
		)
		(property "Device Type" "C805H54"
			(at -0.0762 -8.1534 270)
			(unlocked yes)
			(layer "F.Fab")
			(hide yes)
			(effects
				(font
					(size 1.016 1.016)
					(thickness 0.1524)
				)
			)
		)
		(duplicate_pad_numbers_are_jumpers no)
		(fp_line
			(start 0.635 0)
			(end -0.635 0)
			(stroke
				(width 0.508)
				(type default)
			)
			(layer "F.SilkS")
		)
		(fp_rect
			(start -0.9652 1.778)
			(end 0.9652 -1.778)
			(stroke
				(width 0)
				(type default)
			)
			(fill no)
			(layer "F.CrtYd")
		)
		(fp_poly
			(pts
				(xy -0.9652 -1.778) (xy 0.9652 -1.778) (xy 0.9652 1.778) (xy -0.9652 1.778)
			)
			(stroke
				(width 0)
				(type default)
			)
			(fill no)
			(layer "F.Fab")
		)
		(pad "1" smd rect
			(at 0 -0.9652 270)
			(size 1.397 1.143)
			(layers "F.Cu" "F.Mask" "F.Paste")
			(net "P12V_SCC_PGOOD")
		)
		(pad "2" smd rect
			(at 0 0.9652 270)
			(size 1.397 1.143)
			(layers "F.Cu" "F.Mask" "F.Paste")
			(net "GND")
		)
	)
	(footprint ""
		(layer "F.Cu")
		(at 99.224846 -86.503002 -90)
		(property "Reference" "R77"
			(at 0 0 270)
			(layer "F.SilkS")
			(hide yes)
			(effects
				(font
					(size 1.27 1.27)
				)
			)
		)
		(property "Value" "4K7R2F-GP"
			(at 0.064008 -3.993896 270)
			(unlocked yes)
			(layer "F.Fab")
			(hide yes)
			(effects
				(font
					(size 1.016 1.016)
					(thickness 0.1524)
				)
			)
		)
		(property "Device Type" "R402H16"
			(at 0.064008 -5.517896 270)
			(unlocked yes)
			(layer "F.Fab")
			(hide yes)
			(effects
				(font
					(size 1.016 1.016)
					(thickness 0.1524)
				)
			)
		)
		(duplicate_pad_numbers_are_jumpers no)
		(fp_line
			(start -0.508 -0.9398)
			(end -0.508 0.9398)
			(stroke
				(width 0.1524)
				(type default)
			)
			(layer "F.SilkS")
		)
		(fp_line
			(start 0.508 -0.9398)
			(end -0.508 -0.9398)
			(stroke
				(width 0.1524)
				(type default)
			)
			(layer "F.SilkS")
		)
		(fp_rect
			(start -0.508 0.9398)
			(end 0.508 -0.9398)
			(stroke
				(width 0)
				(type default)
			)
			(fill no)
			(layer "F.CrtYd")
		)
		(fp_rect
			(start -0.508 0.9398)
			(end 0.508 -0.9398)
			(stroke
				(width 0)
				(type default)
			)
			(fill no)
			(layer "F.Fab")
		)
		(pad "1" smd custom
			(at 0 -0.4445 270)
			(size 0.1397 0.1397)
			(layers "F.Cu" "F.Mask" "F.Paste")
			(net "SCC_TYPE_1_LS")
			(options
				(clearance outline)
				(anchor circle)
			)
			(primitives
				(gr_poly
					(pts
						(arc
							(start -0.1778 -0.2794)
							(mid -0.249642 -0.249642)
							(end -0.2794 -0.1778)
						)
						(arc
							(start -0.2794 0.1778)
							(mid -0.249642 0.249642)
							(end -0.1778 0.2794)
						)
						(arc
							(start 0.1778 0.2794)
							(mid 0.249642 0.249642)
							(end 0.2794 0.1778)
						)
						(arc
							(start 0.2794 -0.1778)
							(mid 0.249642 -0.249642)
							(end 0.1778 -0.2794)
						)
					)
					(width 0)
					(fill yes)
				)
			)
		)
		(pad "2" smd custom
			(at 0 0.4445 270)
			(size 0.1397 0.1397)
			(layers "F.Cu" "F.Mask" "F.Paste")
			(net "GND")
			(options
				(clearance outline)
				(anchor circle)
			)
			(primitives
				(gr_poly
					(pts
						(arc
							(start -0.1778 -0.2794)
							(mid -0.249642 -0.249642)
							(end -0.2794 -0.1778)
						)
						(arc
							(start -0.2794 0.1778)
							(mid -0.249642 0.249642)
							(end -0.1778 0.2794)
						)
						(arc
							(start 0.1778 0.2794)
							(mid 0.249642 0.249642)
							(end 0.2794 0.1778)
						)
						(arc
							(start 0.2794 -0.1778)
							(mid 0.249642 -0.249642)
							(end 0.1778 -0.2794)
						)
					)
					(width 0)
					(fill yes)
				)
			)
		)
	)
	(footprint ""
		(layer "F.Cu")
		(at 187.3758 -22.9362 -90)
		(property "Reference" "R270"
			(at 0 0 270)
			(layer "F.SilkS")
			(hide yes)
			(effects
				(font
					(size 1.27 1.27)
				)
			)
		)
		(property "Value" "10KR2F-2-GP"
			(at 0.064008 -3.993896 270)
			(unlocked yes)
			(layer "F.Fab")
			(hide yes)
			(effects
				(font
					(size 1.016 1.016)
					(thickness 0.1524)
				)
			)
		)
		(property "Device Type" "R402H16"
			(at 0.064008 -5.517896 270)
			(unlocked yes)
			(layer "F.Fab")
			(hide yes)
			(effects
				(font
					(size 1.016 1.016)
					(thickness 0.1524)
				)
			)
		)
		(duplicate_pad_numbers_are_jumpers no)
		(fp_line
			(start -0.508 -0.9398)
			(end -0.508 0.9398)
			(stroke
				(width 0.1524)
				(type default)
			)
			(layer "F.SilkS")
		)
		(fp_line
			(start 0.508 -0.9398)
			(end -0.508 -0.9398)
			(stroke
				(width 0.1524)
				(type default)
			)
			(layer "F.SilkS")
		)
		(fp_rect
			(start -0.508 0.9398)
			(end 0.508 -0.9398)
			(stroke
				(width 0)
				(type default)
			)
			(fill no)
			(layer "F.CrtYd")
		)
		(fp_rect
			(start -0.508 0.9398)
			(end 0.508 -0.9398)
			(stroke
				(width 0)
				(type default)
			)
			(fill no)
			(layer "F.Fab")
		)
		(pad "1" smd custom
			(at 0 -0.4445 270)
			(size 0.1397 0.1397)
			(layers "F.Cu" "F.Mask" "F.Paste")
			(net "SYS_DBMODE3")
			(options
				(clearance outline)
				(anchor circle)
			)
			(primitives
				(gr_poly
					(pts
						(arc
							(start -0.1778 -0.2794)
							(mid -0.249642 -0.249642)
							(end -0.2794 -0.1778)
						)
						(arc
							(start -0.2794 0.1778)
							(mid -0.249642 0.249642)
							(end -0.1778 0.2794)
						)
						(arc
							(start 0.1778 0.2794)
							(mid 0.249642 0.249642)
							(end 0.2794 0.1778)
						)
						(arc
							(start 0.2794 -0.1778)
							(mid 0.249642 -0.249642)
							(end 0.1778 -0.2794)
						)
					)
					(width 0)
					(fill yes)
				)
			)
		)
		(pad "2" smd custom
			(at 0 0.4445 270)
			(size 0.1397 0.1397)
			(layers "F.Cu" "F.Mask" "F.Paste")
			(net "GND")
			(options
				(clearance outline)
				(anchor circle)
			)
			(primitives
				(gr_poly
					(pts
						(arc
							(start -0.1778 -0.2794)
							(mid -0.249642 -0.249642)
							(end -0.2794 -0.1778)
						)
						(arc
							(start -0.2794 0.1778)
							(mid -0.249642 0.249642)
							(end -0.1778 0.2794)
						)
						(arc
							(start 0.1778 0.2794)
							(mid 0.249642 0.249642)
							(end 0.2794 0.1778)
						)
						(arc
							(start 0.2794 -0.1778)
							(mid 0.249642 -0.249642)
							(end 0.1778 -0.2794)
						)
					)
					(width 0)
					(fill yes)
				)
			)
		)
	)
	(footprint ""
		(layer "F.Cu")
		(at 92.583 -77.0128 90)
		(property "Reference" "R122"
			(at 0 0 90)
			(layer "F.SilkS")
			(hide yes)
			(effects
				(font
					(size 1.27 1.27)
				)
			)
		)
		(property "Value" "4K75R2F-1-GP"
			(at 0.064008 -3.993896 90)
			(unlocked yes)
			(layer "F.Fab")
			(hide yes)
			(effects
				(font
					(size 1.016 1.016)
					(thickness 0.1524)
				)
			)
		)
		(property "Device Type" "R402H16"
			(at 0.064008 -5.517896 90)
			(unlocked yes)
			(layer "F.Fab")
			(hide yes)
			(effects
				(font
					(size 1.016 1.016)
					(thickness 0.1524)
				)
			)
		)
		(duplicate_pad_numbers_are_jumpers no)
		(fp_line
			(start 0.508 -0.9398)
			(end -0.508 -0.9398)
			(stroke
				(width 0.1524)
				(type default)
			)
			(layer "F.SilkS")
		)
		(fp_line
			(start -0.508 -0.9398)
			(end -0.508 0.9398)
			(stroke
				(width 0.1524)
				(type default)
			)
			(layer "F.SilkS")
		)
		(fp_rect
			(start -0.508 0.9398)
			(end 0.508 -0.9398)
			(stroke
				(width 0)
				(type default)
			)
			(fill no)
			(layer "F.CrtYd")
		)
		(fp_rect
			(start -0.508 0.9398)
			(end 0.508 -0.9398)
			(stroke
				(width 0)
				(type default)
			)
			(fill no)
			(layer "F.Fab")
		)
		(pad "1" smd custom
			(at 0 -0.4445 90)
			(size 0.1397 0.1397)
			(layers "F.Cu" "F.Mask" "F.Paste")
			(net "P1V8_E")
			(options
				(clearance outline)
				(anchor circle)
			)
			(primitives
				(gr_poly
					(pts
						(arc
							(start -0.1778 -0.2794)
							(mid -0.249642 -0.249642)
							(end -0.2794 -0.1778)
						)
						(arc
							(start -0.2794 0.1778)
							(mid -0.249642 0.249642)
							(end -0.1778 0.2794)
						)
						(arc
							(start 0.1778 0.2794)
							(mid 0.249642 0.249642)
							(end 0.2794 0.1778)
						)
						(arc
							(start 0.2794 -0.1778)
							(mid 0.249642 -0.249642)
							(end 0.1778 -0.2794)
						)
					)
					(width 0)
					(fill yes)
				)
			)
		)
		(pad "2" smd custom
			(at 0 0.4445 90)
			(size 0.1397 0.1397)
			(layers "F.Cu" "F.Mask" "F.Paste")
			(net "EXP_CLK_SEL1")
			(options
				(clearance outline)
				(anchor circle)
			)
			(primitives
				(gr_poly
					(pts
						(arc
							(start -0.1778 -0.2794)
							(mid -0.249642 -0.249642)
							(end -0.2794 -0.1778)
						)
						(arc
							(start -0.2794 0.1778)
							(mid -0.249642 0.249642)
							(end -0.1778 0.2794)
						)
						(arc
							(start 0.1778 0.2794)
							(mid 0.249642 0.249642)
							(end 0.2794 0.1778)
						)
						(arc
							(start 0.2794 -0.1778)
							(mid 0.249642 -0.249642)
							(end 0.1778 -0.2794)
						)
					)
					(width 0)
					(fill yes)
				)
			)
		)
	)
	(footprint ""
		(layer "F.Cu")
		(at 191.1858 -24.8412 90)
		(property "Reference" "R271"
			(at 0 0 90)
			(layer "F.SilkS")
			(hide yes)
			(effects
				(font
					(size 1.27 1.27)
				)
			)
		)
		(property "Value" "10KR2F-2-GP"
			(at 0.064008 -3.993896 90)
			(unlocked yes)
			(layer "F.Fab")
			(hide yes)
			(effects
				(font
					(size 1.016 1.016)
					(thickness 0.1524)
				)
			)
		)
		(property "Device Type" "R402H16"
			(at 0.064008 -5.517896 90)
			(unlocked yes)
			(layer "F.Fab")
			(hide yes)
			(effects
				(font
					(size 1.016 1.016)
					(thickness 0.1524)
				)
			)
		)
		(duplicate_pad_numbers_are_jumpers no)
		(fp_line
			(start 0.508 -0.9398)
			(end -0.508 -0.9398)
			(stroke
				(width 0.1524)
				(type default)
			)
			(layer "F.SilkS")
		)
		(fp_line
			(start -0.508 -0.9398)
			(end -0.508 0.9398)
			(stroke
				(width 0.1524)
				(type default)
			)
			(layer "F.SilkS")
		)
		(fp_rect
			(start -0.508 0.9398)
			(end 0.508 -0.9398)
			(stroke
				(width 0)
				(type default)
			)
			(fill no)
			(layer "F.CrtYd")
		)
		(fp_rect
			(start -0.508 0.9398)
			(end 0.508 -0.9398)
			(stroke
				(width 0)
				(type default)
			)
			(fill no)
			(layer "F.Fab")
		)
		(pad "1" smd custom
			(at 0 -0.4445 90)
			(size 0.1397 0.1397)
			(layers "F.Cu" "F.Mask" "F.Paste")
			(net "SYS_DBMODE2")
			(options
				(clearance outline)
				(anchor circle)
			)
			(primitives
				(gr_poly
					(pts
						(arc
							(start -0.1778 -0.2794)
							(mid -0.249642 -0.249642)
							(end -0.2794 -0.1778)
						)
						(arc
							(start -0.2794 0.1778)
							(mid -0.249642 0.249642)
							(end -0.1778 0.2794)
						)
						(arc
							(start 0.1778 0.2794)
							(mid 0.249642 0.249642)
							(end 0.2794 0.1778)
						)
						(arc
							(start 0.2794 -0.1778)
							(mid 0.249642 -0.249642)
							(end 0.1778 -0.2794)
						)
					)
					(width 0)
					(fill yes)
				)
			)
		)
		(pad "2" smd custom
			(at 0 0.4445 90)
			(size 0.1397 0.1397)
			(layers "F.Cu" "F.Mask" "F.Paste")
			(net "GND")
			(options
				(clearance outline)
				(anchor circle)
			)
			(primitives
				(gr_poly
					(pts
						(arc
							(start -0.1778 -0.2794)
							(mid -0.249642 -0.249642)
							(end -0.2794 -0.1778)
						)
						(arc
							(start -0.2794 0.1778)
							(mid -0.249642 0.249642)
							(end -0.1778 0.2794)
						)
						(arc
							(start 0.1778 0.2794)
							(mid 0.249642 0.249642)
							(end 0.2794 0.1778)
						)
						(arc
							(start 0.2794 -0.1778)
							(mid 0.249642 -0.249642)
							(end 0.1778 -0.2794)
						)
					)
					(width 0)
					(fill yes)
				)
			)
		)
	)
	(footprint ""
		(layer "F.Cu")
		(at 169.460164 -55.167276)
		(property "Reference" "TP119"
			(at 0 0 0)
			(layer "F.SilkS")
			(hide yes)
			(effects
				(font
					(size 1.27 1.27)
				)
			)
		)
		(property "Value" "TPAD28-2-GP"
			(at -0.0127 -1.6637 0)
			(unlocked yes)
			(layer "F.Fab")
			(hide yes)
			(effects
				(font
					(size 1.016 1.016)
					(thickness 0.1524)
				)
			)
		)
		(property "Device Type" "TPAD28"
			(at -0.0127 -3.1877 0)
			(unlocked yes)
			(layer "F.Fab")
			(hide yes)
			(effects
				(font
					(size 1.016 1.016)
					(thickness 0.1524)
				)
			)
		)
		(duplicate_pad_numbers_are_jumpers no)
		(fp_poly
			(pts
				(arc
					(start 0.3556 0)
					(mid -0.3556 0)
					(end 0.3556 0)
				)
			)
			(stroke
				(width 0)
				(type default)
			)
			(fill no)
			(layer "F.CrtYd")
		)
		(fp_poly
			(pts
				(arc
					(start 0.6096 0)
					(mid -0.6096 0)
					(end 0.6096 0)
				)
			)
			(stroke
				(width 0)
				(type default)
			)
			(fill no)
			(layer "F.Fab")
		)
		(pad "1" smd circle
			(at 0 0)
			(size 0.7112 0.7112)
			(layers "F.Cu" "F.Mask" "F.Paste")
			(net "ICE0_TCK")
		)
	)
)
